(kicad_pcb
	(version 20260206)
	(generator "pcbnew")
	(generator_version "10.0")
	(general
		(thickness 1.6)
		(legacy_teardrops no)
	)
	(paper "A4")
	(title_block
		(title "01162023_DA0F0TEBIF0_F0T_Expander_BD_F_brd_V02_OCP.brd")
		(comment 1 "Grand Teton / footprints 27-33 of 9728")
	)
	(layers
		(0 "F.Cu" signal "TOP")
		(4 "In1.Cu" signal "GND")
		(6 "In2.Cu" signal "VCC")
		(8 "In3.Cu" signal "VCC1")
		(10 "In4.Cu" signal "GND1")
		(12 "In5.Cu" signal "IN1")
		(14 "In6.Cu" signal "GND2")
		(16 "In7.Cu" signal "IN2")
		(18 "In8.Cu" signal "GND3")
		(20 "In9.Cu" signal "IN3")
		(22 "In10.Cu" signal "GND4")
		(24 "In11.Cu" signal "IN4")
		(26 "In12.Cu" signal "GND5")
		(28 "In13.Cu" signal "IN5")
		(30 "In14.Cu" signal "GND6")
		(32 "In15.Cu" signal "IN6")
		(34 "In16.Cu" signal "GND7")
		(2 "B.Cu" signal "BOTTOM")
		(9 "F.Adhes" user "F.Adhesive")
		(11 "B.Adhes" user "B.Adhesive")
		(13 "F.Paste" user "Package Geometry/Pastemask Top")
		(15 "B.Paste" user "Package Geometry/Pastemask Bottom")
		(5 "F.SilkS" user "Ref Des/Silkscreen Top")
		(7 "B.SilkS" user "Ref Des/Silkscreen Bottom")
		(1 "F.Mask" user "Board Geometry/Soldermask Top")
		(3 "B.Mask" user "Board Geometry/Soldermask Bottom")
		(17 "Dwgs.User" user "User.Drawings")
		(19 "Cmts.User" user "User.Comments")
		(21 "Eco1.User" user "User.Eco1")
		(23 "Eco2.User" user "User.Eco2")
		(25 "Edge.Cuts" user "Board Geometry/Outline")
		(27 "Margin" user)
		(31 "F.CrtYd" user "Package Geometry/Place Bound Top")
		(29 "B.CrtYd" user "Package Geometry/Place Bound Bottom")
		(35 "F.Fab" user "Ref Des/Assembly Top")
		(33 "B.Fab" user "Ref Des/Assembly Bottom")
	)
	(footprint ""
		(layer "F.Cu")
		(at 337.947 -234.061 90)
		(property "Reference" "R3555"
			(at 0 0 90)
			(layer "F.SilkS")
			(hide yes)
			(effects
				(font
					(size 1.27 1.27)
				)
			)
		)
		(property "Value" ""
			(at 0 0 90)
			(layer "F.Fab")
			(effects
				(font
					(size 1.27 1.27)
				)
			)
		)
		(duplicate_pad_numbers_are_jumpers no)
		(fp_line
			(start 0.7874 -0.4064)
			(end 0.7874 0.4064)
			(stroke
				(width 0.1524)
				(type default)
			)
			(layer "F.SilkS")
		)
		(fp_line
			(start -0.7874 -0.4064)
			(end 0.7874 -0.4064)
			(stroke
				(width 0.1524)
				(type default)
			)
			(layer "F.SilkS")
		)
		(fp_line
			(start 0.7874 0.4064)
			(end -0.7874 0.4064)
			(stroke
				(width 0.1524)
				(type default)
			)
			(layer "F.SilkS")
		)
		(fp_line
			(start -0.7874 0.4064)
			(end -0.7874 -0.4064)
			(stroke
				(width 0.1524)
				(type default)
			)
			(layer "F.SilkS")
		)
		(fp_line
			(start -0.12065 -0.305054)
			(end -0.12065 -0.2794)
			(stroke
				(width 0.1)
				(type default)
			)
			(layer "F.Fab")
		)
		(fp_line
			(start -0.67945 -0.305054)
			(end -0.12065 -0.305054)
			(stroke
				(width 0.1)
				(type default)
			)
			(layer "F.Fab")
		)
		(fp_line
			(start 0.67945 -0.3048)
			(end 0.67945 0.3048)
			(stroke
				(width 0.1)
				(type default)
			)
			(layer "F.Fab")
		)
		(fp_line
			(start 0.12065 -0.3048)
			(end 0.67945 -0.3048)
			(stroke
				(width 0.1)
				(type default)
			)
			(layer "F.Fab")
		)
		(fp_line
			(start 0.12065 -0.2794)
			(end 0.12065 -0.3048)
			(stroke
				(width 0.1)
				(type default)
			)
			(layer "F.Fab")
		)
		(fp_line
			(start -0.12065 -0.2794)
			(end 0.12065 -0.2794)
			(stroke
				(width 0.1)
				(type default)
			)
			(layer "F.Fab")
		)
		(fp_line
			(start 0.120396 0.2794)
			(end -0.12065 0.2794)
			(stroke
				(width 0.1)
				(type default)
			)
			(layer "F.Fab")
		)
		(fp_line
			(start -0.12065 0.2794)
			(end -0.12065 0.3048)
			(stroke
				(width 0.1)
				(type default)
			)
			(layer "F.Fab")
		)
		(fp_line
			(start 0.67945 0.3048)
			(end 0.120396 0.3048)
			(stroke
				(width 0.1)
				(type default)
			)
			(layer "F.Fab")
		)
		(fp_line
			(start 0.120396 0.3048)
			(end 0.120396 0.2794)
			(stroke
				(width 0.1)
				(type default)
			)
			(layer "F.Fab")
		)
		(fp_line
			(start -0.12065 0.3048)
			(end -0.67945 0.3048)
			(stroke
				(width 0.1)
				(type default)
			)
			(layer "F.Fab")
		)
		(fp_line
			(start -0.67945 0.3048)
			(end -0.67945 -0.305054)
			(stroke
				(width 0.1)
				(type default)
			)
			(layer "F.Fab")
		)
		(pad "1" smd circle
			(at -0.40005 0 90)
			(size 0 0)
			(layers "F.Cu" "F.Mask" "F.Paste")
			(net "FM_SOL_UART_CH_SEL_R")
		)
		(pad "2" smd circle
			(at 0.40005 0 90)
			(size 0 0)
			(layers "F.Cu" "F.Mask" "F.Paste")
			(net "FM_SOL_UART_CH_SEL")
		)
	)
	(footprint ""
		(layer "F.Cu")
		(at 127.658114 -257.115564)
		(property "Reference" "PR83"
			(at 0 0 0)
			(layer "F.SilkS")
			(hide yes)
			(effects
				(font
					(size 1.27 1.27)
				)
			)
		)
		(property "Value" ""
			(at 0 0 0)
			(layer "F.Fab")
			(effects
				(font
					(size 1.27 1.27)
				)
			)
		)
		(duplicate_pad_numbers_are_jumpers no)
		(fp_line
			(start -0.7874 -0.4064)
			(end 0.7874 -0.4064)
			(stroke
				(width 0.1524)
				(type default)
			)
			(layer "F.SilkS")
		)
		(fp_line
			(start -0.7874 0.4064)
			(end -0.7874 -0.4064)
			(stroke
				(width 0.1524)
				(type default)
			)
			(layer "F.SilkS")
		)
		(fp_line
			(start 0.7874 -0.4064)
			(end 0.7874 0.4064)
			(stroke
				(width 0.1524)
				(type default)
			)
			(layer "F.SilkS")
		)
		(fp_line
			(start 0.7874 0.4064)
			(end -0.7874 0.4064)
			(stroke
				(width 0.1524)
				(type default)
			)
			(layer "F.SilkS")
		)
		(fp_line
			(start -0.67945 -0.305054)
			(end -0.12065 -0.305054)
			(stroke
				(width 0.1)
				(type default)
			)
			(layer "F.Fab")
		)
		(fp_line
			(start -0.67945 0.3048)
			(end -0.67945 -0.305054)
			(stroke
				(width 0.1)
				(type default)
			)
			(layer "F.Fab")
		)
		(fp_line
			(start -0.12065 -0.305054)
			(end -0.12065 -0.2794)
			(stroke
				(width 0.1)
				(type default)
			)
			(layer "F.Fab")
		)
		(fp_line
			(start -0.12065 -0.2794)
			(end 0.12065 -0.2794)
			(stroke
				(width 0.1)
				(type default)
			)
			(layer "F.Fab")
		)
		(fp_line
			(start -0.12065 0.2794)
			(end -0.12065 0.3048)
			(stroke
				(width 0.1)
				(type default)
			)
			(layer "F.Fab")
		)
		(fp_line
			(start -0.12065 0.3048)
			(end -0.67945 0.3048)
			(stroke
				(width 0.1)
				(type default)
			)
			(layer "F.Fab")
		)
		(fp_line
			(start 0.120396 0.2794)
			(end -0.12065 0.2794)
			(stroke
				(width 0.1)
				(type default)
			)
			(layer "F.Fab")
		)
		(fp_line
			(start 0.120396 0.3048)
			(end 0.120396 0.2794)
			(stroke
				(width 0.1)
				(type default)
			)
			(layer "F.Fab")
		)
		(fp_line
			(start 0.12065 -0.3048)
			(end 0.67945 -0.3048)
			(stroke
				(width 0.1)
				(type default)
			)
			(layer "F.Fab")
		)
		(fp_line
			(start 0.12065 -0.2794)
			(end 0.12065 -0.3048)
			(stroke
				(width 0.1)
				(type default)
			)
			(layer "F.Fab")
		)
		(fp_line
			(start 0.67945 -0.3048)
			(end 0.67945 0.3048)
			(stroke
				(width 0.1)
				(type default)
			)
			(layer "F.Fab")
		)
		(fp_line
			(start 0.67945 0.3048)
			(end 0.120396 0.3048)
			(stroke
				(width 0.1)
				(type default)
			)
			(layer "F.Fab")
		)
		(pad "1" smd circle
			(at -0.40005 0)
			(size 0 0)
			(layers "F.Cu" "F.Mask" "F.Paste")
			(net "P0V8_PEX0_PINALRT")
		)
		(pad "2" smd circle
			(at 0.40005 0)
			(size 0 0)
			(layers "F.Cu" "F.Mask" "F.Paste")
			(net "P3V3_AUX")
		)
	)
	(footprint ""
		(layer "F.Cu")
		(at 258.46786 -54.067456)
		(property "Reference" "PR225"
			(at 0 0 0)
			(layer "F.SilkS")
			(hide yes)
			(effects
				(font
					(size 1.27 1.27)
				)
			)
		)
		(property "Value" ""
			(at 0 0 0)
			(layer "F.Fab")
			(effects
				(font
					(size 1.27 1.27)
				)
			)
		)
		(duplicate_pad_numbers_are_jumpers no)
		(fp_line
			(start -0.7874 -0.4064)
			(end 0.7874 -0.4064)
			(stroke
				(width 0.1524)
				(type default)
			)
			(layer "F.SilkS")
		)
		(fp_line
			(start -0.7874 0.4064)
			(end -0.7874 -0.4064)
			(stroke
				(width 0.1524)
				(type default)
			)
			(layer "F.SilkS")
		)
		(fp_line
			(start 0.7874 -0.4064)
			(end 0.7874 0.4064)
			(stroke
				(width 0.1524)
				(type default)
			)
			(layer "F.SilkS")
		)
		(fp_line
			(start 0.7874 0.4064)
			(end -0.7874 0.4064)
			(stroke
				(width 0.1524)
				(type default)
			)
			(layer "F.SilkS")
		)
		(fp_line
			(start -0.67945 -0.305054)
			(end -0.12065 -0.305054)
			(stroke
				(width 0.1)
				(type default)
			)
			(layer "F.Fab")
		)
		(fp_line
			(start -0.67945 0.3048)
			(end -0.67945 -0.305054)
			(stroke
				(width 0.1)
				(type default)
			)
			(layer "F.Fab")
		)
		(fp_line
			(start -0.12065 -0.305054)
			(end -0.12065 -0.2794)
			(stroke
				(width 0.1)
				(type default)
			)
			(layer "F.Fab")
		)
		(fp_line
			(start -0.12065 -0.2794)
			(end 0.12065 -0.2794)
			(stroke
				(width 0.1)
				(type default)
			)
			(layer "F.Fab")
		)
		(fp_line
			(start -0.12065 0.2794)
			(end -0.12065 0.3048)
			(stroke
				(width 0.1)
				(type default)
			)
			(layer "F.Fab")
		)
		(fp_line
			(start -0.12065 0.3048)
			(end -0.67945 0.3048)
			(stroke
				(width 0.1)
				(type default)
			)
			(layer "F.Fab")
		)
		(fp_line
			(start 0.120396 0.2794)
			(end -0.12065 0.2794)
			(stroke
				(width 0.1)
				(type default)
			)
			(layer "F.Fab")
		)
		(fp_line
			(start 0.120396 0.3048)
			(end 0.120396 0.2794)
			(stroke
				(width 0.1)
				(type default)
			)
			(layer "F.Fab")
		)
		(fp_line
			(start 0.12065 -0.3048)
			(end 0.67945 -0.3048)
			(stroke
				(width 0.1)
				(type default)
			)
			(layer "F.Fab")
		)
		(fp_line
			(start 0.12065 -0.2794)
			(end 0.12065 -0.3048)
			(stroke
				(width 0.1)
				(type default)
			)
			(layer "F.Fab")
		)
		(fp_line
			(start 0.67945 -0.3048)
			(end 0.67945 0.3048)
			(stroke
				(width 0.1)
				(type default)
			)
			(layer "F.Fab")
		)
		(fp_line
			(start 0.67945 0.3048)
			(end 0.120396 0.3048)
			(stroke
				(width 0.1)
				(type default)
			)
			(layer "F.Fab")
		)
		(pad "1" smd circle
			(at -0.40005 0)
			(size 0 0)
			(layers "F.Cu" "F.Mask" "F.Paste")
			(net "P12V_SSD8_OCP")
		)
		(pad "2" smd circle
			(at 0.40005 0)
			(size 0 0)
			(layers "F.Cu" "F.Mask" "F.Paste")
			(net "GND")
		)
	)
	(footprint ""
		(layer "F.Cu")
		(at 312.21934 -129.880106 180)
		(property "Reference" "C446"
			(at 0 0 180)
			(layer "F.SilkS")
			(hide yes)
			(effects
				(font
					(size 1.27 1.27)
				)
			)
		)
		(property "Value" ""
			(at 0 0 180)
			(layer "F.Fab")
			(effects
				(font
					(size 1.27 1.27)
				)
			)
		)
		(duplicate_pad_numbers_are_jumpers no)
		(fp_line
			(start 0.299974 0.150114)
			(end -0.299974 0.150114)
			(stroke
				(width 0.1)
				(type default)
			)
			(layer "F.Fab")
		)
		(fp_line
			(start 0.299974 -0.150114)
			(end 0.299974 0.150114)
			(stroke
				(width 0.1)
				(type default)
			)
			(layer "F.Fab")
		)
		(fp_line
			(start -0.299974 0.150114)
			(end -0.299974 -0.150114)
			(stroke
				(width 0.1)
				(type default)
			)
			(layer "F.Fab")
		)
		(fp_line
			(start -0.299974 -0.150114)
			(end 0.299974 -0.150114)
			(stroke
				(width 0.1)
				(type default)
			)
			(layer "F.Fab")
		)
		(pad "1" smd rect
			(at -0.2667 0 180)
			(size 0.3048 0.381)
			(layers "F.Cu" "F.Mask" "F.Paste")
			(net "P5E_PEX2_STN0_TX_DN<4>")
		)
		(pad "2" smd rect
			(at 0.2667 0 180)
			(size 0.3048 0.381)
			(layers "F.Cu" "F.Mask" "F.Paste")
			(net "P5E_PEX2_STN0_TX_C_DN<4>")
		)
	)
	(footprint ""
		(layer "F.Cu")
		(at 459.04658 -373.852948 -90)
		(property "Reference" "C4453"
			(at 0 0 270)
			(layer "F.SilkS")
			(hide yes)
			(effects
				(font
					(size 1.27 1.27)
				)
			)
		)
		(property "Value" ""
			(at 0 0 270)
			(layer "F.Fab")
			(effects
				(font
					(size 1.27 1.27)
				)
			)
		)
		(duplicate_pad_numbers_are_jumpers no)
		(fp_line
			(start -0.299974 0.150114)
			(end -0.299974 -0.150114)
			(stroke
				(width 0.1)
				(type default)
			)
			(layer "F.Fab")
		)
		(fp_line
			(start 0.299974 0.150114)
			(end -0.299974 0.150114)
			(stroke
				(width 0.1)
				(type default)
			)
			(layer "F.Fab")
		)
		(fp_line
			(start -0.299974 -0.150114)
			(end 0.299974 -0.150114)
			(stroke
				(width 0.1)
				(type default)
			)
			(layer "F.Fab")
		)
		(fp_line
			(start 0.299974 -0.150114)
			(end 0.299974 0.150114)
			(stroke
				(width 0.1)
				(type default)
			)
			(layer "F.Fab")
		)
		(pad "1" smd rect
			(at -0.2667 0 270)
			(size 0.3048 0.381)
			(layers "F.Cu" "F.Mask" "F.Paste")
			(net "GPU_3V3IO_RSVD3_ISO")
		)
		(pad "2" smd rect
			(at 0.2667 0 270)
			(size 0.3048 0.381)
			(layers "F.Cu" "F.Mask" "F.Paste")
			(net "GND")
		)
	)
	(footprint ""
		(layer "F.Cu")
		(at 188.773054 -22.867366 90)
		(property "Reference" "C3914"
			(at 0 0 90)
			(layer "F.SilkS")
			(hide yes)
			(effects
				(font
					(size 1.27 1.27)
				)
			)
		)
		(property "Value" ""
			(at 0 0 90)
			(layer "F.Fab")
			(effects
				(font
					(size 1.27 1.27)
				)
			)
		)
		(duplicate_pad_numbers_are_jumpers no)
		(fp_line
			(start 0.7874 -0.4064)
			(end 0.7874 0.4064)
			(stroke
				(width 0.1524)
				(type default)
			)
			(layer "F.SilkS")
		)
		(fp_line
			(start -0.7874 -0.4064)
			(end 0.7874 -0.4064)
			(stroke
				(width 0.1524)
				(type default)
			)
			(layer "F.SilkS")
		)
		(fp_line
			(start 0.7874 0.4064)
			(end -0.7874 0.4064)
			(stroke
				(width 0.1524)
				(type default)
			)
			(layer "F.SilkS")
		)
		(fp_line
			(start -0.7874 0.4064)
			(end -0.7874 -0.4064)
			(stroke
				(width 0.1524)
				(type default)
			)
			(layer "F.SilkS")
		)
		(fp_line
			(start -0.12065 -0.305054)
			(end -0.12065 -0.2794)
			(stroke
				(width 0.1)
				(type default)
			)
			(layer "F.Fab")
		)
		(fp_line
			(start -0.67945 -0.305054)
			(end -0.12065 -0.305054)
			(stroke
				(width 0.1)
				(type default)
			)
			(layer "F.Fab")
		)
		(fp_line
			(start 0.67945 -0.3048)
			(end 0.67945 0.3048)
			(stroke
				(width 0.1)
				(type default)
			)
			(layer "F.Fab")
		)
		(fp_line
			(start 0.12065 -0.3048)
			(end 0.67945 -0.3048)
			(stroke
				(width 0.1)
				(type default)
			)
			(layer "F.Fab")
		)
		(fp_line
			(start 0.12065 -0.2794)
			(end 0.12065 -0.3048)
			(stroke
				(width 0.1)
				(type default)
			)
			(layer "F.Fab")
		)
		(fp_line
			(start -0.12065 -0.2794)
			(end 0.12065 -0.2794)
			(stroke
				(width 0.1)
				(type default)
			)
			(layer "F.Fab")
		)
		(fp_line
			(start 0.120396 0.2794)
			(end -0.12065 0.2794)
			(stroke
				(width 0.1)
				(type default)
			)
			(layer "F.Fab")
		)
		(fp_line
			(start -0.12065 0.2794)
			(end -0.12065 0.3048)
			(stroke
				(width 0.1)
				(type default)
			)
			(layer "F.Fab")
		)
		(fp_line
			(start 0.67945 0.3048)
			(end 0.120396 0.3048)
			(stroke
				(width 0.1)
				(type default)
			)
			(layer "F.Fab")
		)
		(fp_line
			(start 0.120396 0.3048)
			(end 0.120396 0.2794)
			(stroke
				(width 0.1)
				(type default)
			)
			(layer "F.Fab")
		)
		(fp_line
			(start -0.12065 0.3048)
			(end -0.67945 0.3048)
			(stroke
				(width 0.1)
				(type default)
			)
			(layer "F.Fab")
		)
		(fp_line
			(start -0.67945 0.3048)
			(end -0.67945 -0.305054)
			(stroke
				(width 0.1)
				(type default)
			)
			(layer "F.Fab")
		)
		(pad "1" smd circle
			(at -0.40005 0 90)
			(size 0 0)
			(layers "F.Cu" "F.Mask" "F.Paste")
			(net "P12V_SSD6")
		)
		(pad "2" smd circle
			(at 0.40005 0 90)
			(size 0 0)
			(layers "F.Cu" "F.Mask" "F.Paste")
			(net "GND")
		)
	)
	(footprint ""
		(layer "F.Cu")
		(at 329.03414 -95.263716 -90)
		(property "Reference" "R4447"
			(at 0 0 270)
			(layer "F.SilkS")
			(hide yes)
			(effects
				(font
					(size 1.27 1.27)
				)
			)
		)
		(property "Value" ""
			(at 0 0 270)
			(layer "F.Fab")
			(effects
				(font
					(size 1.27 1.27)
				)
			)
		)
		(duplicate_pad_numbers_are_jumpers no)
		(fp_line
			(start -0.7874 0.4064)
			(end -0.7874 -0.4064)
			(stroke
				(width 0.1524)
				(type default)
			)
			(layer "F.SilkS")
		)
		(fp_line
			(start 0.7874 0.4064)
			(end -0.7874 0.4064)
			(stroke
				(width 0.1524)
				(type default)
			)
			(layer "F.SilkS")
		)
		(fp_line
			(start -0.7874 -0.4064)
			(end 0.7874 -0.4064)
			(stroke
				(width 0.1524)
				(type default)
			)
			(layer "F.SilkS")
		)
		(fp_line
			(start 0.7874 -0.4064)
			(end 0.7874 0.4064)
			(stroke
				(width 0.1524)
				(type default)
			)
			(layer "F.SilkS")
		)
		(fp_line
			(start -0.67945 0.3048)
			(end -0.67945 -0.305054)
			(stroke
				(width 0.1)
				(type default)
			)
			(layer "F.Fab")
		)
		(fp_line
			(start -0.12065 0.3048)
			(end -0.67945 0.3048)
			(stroke
				(width 0.1)
				(type default)
			)
			(layer "F.Fab")
		)
		(fp_line
			(start 0.120396 0.3048)
			(end 0.120396 0.2794)
			(stroke
				(width 0.1)
				(type default)
			)
			(layer "F.Fab")
		)
		(fp_line
			(start 0.67945 0.3048)
			(end 0.120396 0.3048)
			(stroke
				(width 0.1)
				(type default)
			)
			(layer "F.Fab")
		)
		(fp_line
			(start -0.12065 0.2794)
			(end -0.12065 0.3048)
			(stroke
				(width 0.1)
				(type default)
			)
			(layer "F.Fab")
		)
		(fp_line
			(start 0.120396 0.2794)
			(end -0.12065 0.2794)
			(stroke
				(width 0.1)
				(type default)
			)
			(layer "F.Fab")
		)
		(fp_line
			(start -0.12065 -0.2794)
			(end 0.12065 -0.2794)
			(stroke
				(width 0.1)
				(type default)
			)
			(layer "F.Fab")
		)
		(fp_line
			(start 0.12065 -0.2794)
			(end 0.12065 -0.3048)
			(stroke
				(width 0.1)
				(type default)
			)
			(layer "F.Fab")
		)
		(fp_line
			(start 0.12065 -0.3048)
			(end 0.67945 -0.3048)
			(stroke
				(width 0.1)
				(type default)
			)
			(layer "F.Fab")
		)
		(fp_line
			(start 0.67945 -0.3048)
			(end 0.67945 0.3048)
			(stroke
				(width 0.1)
				(type default)
			)
			(layer "F.Fab")
		)
		(fp_line
			(start -0.67945 -0.305054)
			(end -0.12065 -0.305054)
			(stroke
				(width 0.1)
				(type default)
			)
			(layer "F.Fab")
		)
		(fp_line
			(start -0.12065 -0.305054)
			(end -0.12065 -0.2794)
			(stroke
				(width 0.1)
				(type default)
			)
			(layer "F.Fab")
		)
		(pad "1" smd circle
			(at -0.40005 0 270)
			(size 0 0)
			(layers "F.Cu" "F.Mask" "F.Paste")
			(net "PWRGD_P12V_NIC5")
		)
		(pad "2" smd circle
			(at 0.40005 0 270)
			(size 0 0)
			(layers "F.Cu" "F.Mask" "F.Paste")
			(net "PWRGD_P12V_NIC5_R")
		)
	)
)
